(kicad_pcb
	(version 20260206)
	(generator "pcbnew")
	(generator_version "10.0")
	(general
		(thickness 1.6)
		(legacy_teardrops no)
	)
	(paper "A4")
	(title_block
		(title "04192023_DAF0TMB3IC0_F0TG_MB_C_brd_V02_OCP.brd")
		(comment 1 "Grand Teton / footprints 2443-2448 of 8354")
	)
	(layers
		(0 "F.Cu" signal "TOP")
		(4 "In1.Cu" signal "GND")
		(6 "In2.Cu" signal "IN1")
		(8 "In3.Cu" signal "GND1")
		(10 "In4.Cu" signal "IN2")
		(12 "In5.Cu" signal "GND2")
		(14 "In6.Cu" signal "IN3")
		(16 "In7.Cu" signal "GND3")
		(18 "In8.Cu" signal "VCC")
		(20 "In9.Cu" signal "VCC1")
		(22 "In10.Cu" signal "GND4")
		(24 "In11.Cu" signal "IN4")
		(26 "In12.Cu" signal "GND5")
		(28 "In13.Cu" signal "IN5")
		(30 "In14.Cu" signal "GND6")
		(32 "In15.Cu" signal "IN6")
		(34 "In16.Cu" signal "GND7")
		(2 "B.Cu" signal "BOTTOM")
		(9 "F.Adhes" user "F.Adhesive")
		(11 "B.Adhes" user "B.Adhesive")
		(13 "F.Paste" user "Package Geometry/Pastemask Top")
		(15 "B.Paste" user "Package Geometry/Pastemask Bottom")
		(5 "F.SilkS" user "Ref Des/Silkscreen Top")
		(7 "B.SilkS" user "Ref Des/Silkscreen Bottom")
		(1 "F.Mask" user "Board Geometry/Soldermask Top")
		(3 "B.Mask" user "Board Geometry/Soldermask Bottom")
		(17 "Dwgs.User" user "User.Drawings")
		(19 "Cmts.User" user "User.Comments")
		(21 "Eco1.User" user "User.Eco1")
		(23 "Eco2.User" user "User.Eco2")
		(25 "Edge.Cuts" user "Board Geometry/Outline")
		(27 "Margin" user)
		(31 "F.CrtYd" user "Package Geometry/Place Bound Top")
		(29 "B.CrtYd" user "Package Geometry/Place Bound Bottom")
		(35 "F.Fab" user "Ref Des/Assembly Top")
		(33 "B.Fab" user "Ref Des/Assembly Bottom")
	)
	(footprint ""
		(layer "F.Cu")
		(at 342.442546 -23.897336 -90)
		(property "Reference" "R946"
			(at 0 0 270)
			(layer "F.SilkS")
			(hide yes)
			(effects
				(font
					(size 1.27 1.27)
				)
			)
		)
		(property "Value" ""
			(at 0 0 270)
			(layer "F.Fab")
			(effects
				(font
					(size 1.27 1.27)
				)
			)
		)
		(duplicate_pad_numbers_are_jumpers no)
		(fp_line
			(start -0.7874 0.4064)
			(end -0.7874 -0.4064)
			(stroke
				(width 0.1524)
				(type default)
			)
			(layer "F.SilkS")
		)
		(fp_line
			(start 0.7874 0.4064)
			(end -0.7874 0.4064)
			(stroke
				(width 0.1524)
				(type default)
			)
			(layer "F.SilkS")
		)
		(fp_line
			(start -0.7874 -0.4064)
			(end 0.7874 -0.4064)
			(stroke
				(width 0.1524)
				(type default)
			)
			(layer "F.SilkS")
		)
		(fp_line
			(start 0.7874 -0.4064)
			(end 0.7874 0.4064)
			(stroke
				(width 0.1524)
				(type default)
			)
			(layer "F.SilkS")
		)
		(fp_line
			(start -0.67945 0.3048)
			(end -0.67945 -0.305054)
			(stroke
				(width 0.1)
				(type default)
			)
			(layer "F.Fab")
		)
		(fp_line
			(start -0.12065 0.3048)
			(end -0.67945 0.3048)
			(stroke
				(width 0.1)
				(type default)
			)
			(layer "F.Fab")
		)
		(fp_line
			(start 0.120396 0.3048)
			(end 0.120396 0.2794)
			(stroke
				(width 0.1)
				(type default)
			)
			(layer "F.Fab")
		)
		(fp_line
			(start 0.67945 0.3048)
			(end 0.120396 0.3048)
			(stroke
				(width 0.1)
				(type default)
			)
			(layer "F.Fab")
		)
		(fp_line
			(start -0.12065 0.2794)
			(end -0.12065 0.3048)
			(stroke
				(width 0.1)
				(type default)
			)
			(layer "F.Fab")
		)
		(fp_line
			(start 0.120396 0.2794)
			(end -0.12065 0.2794)
			(stroke
				(width 0.1)
				(type default)
			)
			(layer "F.Fab")
		)
		(fp_line
			(start -0.12065 -0.2794)
			(end 0.12065 -0.2794)
			(stroke
				(width 0.1)
				(type default)
			)
			(layer "F.Fab")
		)
		(fp_line
			(start 0.12065 -0.2794)
			(end 0.12065 -0.3048)
			(stroke
				(width 0.1)
				(type default)
			)
			(layer "F.Fab")
		)
		(fp_line
			(start 0.12065 -0.3048)
			(end 0.67945 -0.3048)
			(stroke
				(width 0.1)
				(type default)
			)
			(layer "F.Fab")
		)
		(fp_line
			(start 0.67945 -0.3048)
			(end 0.67945 0.3048)
			(stroke
				(width 0.1)
				(type default)
			)
			(layer "F.Fab")
		)
		(fp_line
			(start -0.67945 -0.305054)
			(end -0.12065 -0.305054)
			(stroke
				(width 0.1)
				(type default)
			)
			(layer "F.Fab")
		)
		(fp_line
			(start -0.12065 -0.305054)
			(end -0.12065 -0.2794)
			(stroke
				(width 0.1)
				(type default)
			)
			(layer "F.Fab")
		)
		(pad "1" smd circle
			(at -0.40005 0 270)
			(size 0 0)
			(layers "F.Cu" "F.Mask" "F.Paste")
			(net "P3V3_AUX")
		)
		(pad "2" smd circle
			(at 0.40005 0 270)
			(size 0 0)
			(layers "F.Cu" "F.Mask" "F.Paste")
			(net "BOOT_RDY_LED")
		)
	)
	(footprint ""
		(layer "F.Cu")
		(at 166.8272 -429.9712 90)
		(property "Reference" "R2667"
			(at 0 0 90)
			(layer "F.SilkS")
			(hide yes)
			(effects
				(font
					(size 1.27 1.27)
				)
			)
		)
		(property "Value" ""
			(at 0 0 90)
			(layer "F.Fab")
			(effects
				(font
					(size 1.27 1.27)
				)
			)
		)
		(duplicate_pad_numbers_are_jumpers no)
		(fp_line
			(start 0.7874 -0.4064)
			(end 0.7874 0.4064)
			(stroke
				(width 0.1524)
				(type default)
			)
			(layer "F.SilkS")
		)
		(fp_line
			(start -0.7874 -0.4064)
			(end 0.7874 -0.4064)
			(stroke
				(width 0.1524)
				(type default)
			)
			(layer "F.SilkS")
		)
		(fp_line
			(start 0.7874 0.4064)
			(end -0.7874 0.4064)
			(stroke
				(width 0.1524)
				(type default)
			)
			(layer "F.SilkS")
		)
		(fp_line
			(start -0.7874 0.4064)
			(end -0.7874 -0.4064)
			(stroke
				(width 0.1524)
				(type default)
			)
			(layer "F.SilkS")
		)
		(fp_line
			(start -0.12065 -0.305054)
			(end -0.12065 -0.2794)
			(stroke
				(width 0.1)
				(type default)
			)
			(layer "F.Fab")
		)
		(fp_line
			(start -0.67945 -0.305054)
			(end -0.12065 -0.305054)
			(stroke
				(width 0.1)
				(type default)
			)
			(layer "F.Fab")
		)
		(fp_line
			(start 0.67945 -0.3048)
			(end 0.67945 0.3048)
			(stroke
				(width 0.1)
				(type default)
			)
			(layer "F.Fab")
		)
		(fp_line
			(start 0.12065 -0.3048)
			(end 0.67945 -0.3048)
			(stroke
				(width 0.1)
				(type default)
			)
			(layer "F.Fab")
		)
		(fp_line
			(start 0.12065 -0.2794)
			(end 0.12065 -0.3048)
			(stroke
				(width 0.1)
				(type default)
			)
			(layer "F.Fab")
		)
		(fp_line
			(start -0.12065 -0.2794)
			(end 0.12065 -0.2794)
			(stroke
				(width 0.1)
				(type default)
			)
			(layer "F.Fab")
		)
		(fp_line
			(start 0.120396 0.2794)
			(end -0.12065 0.2794)
			(stroke
				(width 0.1)
				(type default)
			)
			(layer "F.Fab")
		)
		(fp_line
			(start -0.12065 0.2794)
			(end -0.12065 0.3048)
			(stroke
				(width 0.1)
				(type default)
			)
			(layer "F.Fab")
		)
		(fp_line
			(start 0.67945 0.3048)
			(end 0.120396 0.3048)
			(stroke
				(width 0.1)
				(type default)
			)
			(layer "F.Fab")
		)
		(fp_line
			(start 0.120396 0.3048)
			(end 0.120396 0.2794)
			(stroke
				(width 0.1)
				(type default)
			)
			(layer "F.Fab")
		)
		(fp_line
			(start -0.12065 0.3048)
			(end -0.67945 0.3048)
			(stroke
				(width 0.1)
				(type default)
			)
			(layer "F.Fab")
		)
		(fp_line
			(start -0.67945 0.3048)
			(end -0.67945 -0.305054)
			(stroke
				(width 0.1)
				(type default)
			)
			(layer "F.Fab")
		)
		(pad "1" smd circle
			(at -0.40005 0 90)
			(size 0 0)
			(layers "F.Cu" "F.Mask" "F.Paste")
			(net "P3V3_AUX")
		)
		(pad "2" smd circle
			(at 0.40005 0 90)
			(size 0 0)
			(layers "F.Cu" "F.Mask" "F.Paste")
			(net "SMB_BMC_SWB_BUF_R_SCL")
		)
	)
	(footprint ""
		(layer "F.Cu")
		(at 169.1894 -332.244192 180)
		(property "Reference" "TP13"
			(at 2.356612 5.244846 0)
			(unlocked yes)
			(layer "F.SilkS")
			(effects
				(font
					(size 0.7874 0.5842)
					(thickness 0.1524)
				)
				(justify left)
			)
		)
		(property "Value" ""
			(at 0 0 180)
			(layer "F.Fab")
			(effects
				(font
					(size 1.27 1.27)
				)
			)
		)
		(duplicate_pad_numbers_are_jumpers no)
		(pad "1" smd circle
			(at 0 0 180)
			(size 0.762 0.762)
			(layers "F.Cu" "F.Mask" "F.Paste")
			(net "VSENSE_VSS_SENSE_C_P1")
		)
	)
	(footprint ""
		(layer "F.Cu")
		(at 444.733172 -32.173418 -90)
		(property "Reference" "R3834"
			(at 0 0 270)
			(layer "F.SilkS")
			(hide yes)
			(effects
				(font
					(size 1.27 1.27)
				)
			)
		)
		(property "Value" ""
			(at 0 0 270)
			(layer "F.Fab")
			(effects
				(font
					(size 1.27 1.27)
				)
			)
		)
		(duplicate_pad_numbers_are_jumpers no)
		(fp_line
			(start -0.7874 0.4064)
			(end -0.7874 -0.4064)
			(stroke
				(width 0.1524)
				(type default)
			)
			(layer "F.SilkS")
		)
		(fp_line
			(start 0.7874 0.4064)
			(end -0.7874 0.4064)
			(stroke
				(width 0.1524)
				(type default)
			)
			(layer "F.SilkS")
		)
		(fp_line
			(start -0.7874 -0.4064)
			(end 0.7874 -0.4064)
			(stroke
				(width 0.1524)
				(type default)
			)
			(layer "F.SilkS")
		)
		(fp_line
			(start 0.7874 -0.4064)
			(end 0.7874 0.4064)
			(stroke
				(width 0.1524)
				(type default)
			)
			(layer "F.SilkS")
		)
		(fp_line
			(start -0.67945 0.3048)
			(end -0.67945 -0.305054)
			(stroke
				(width 0.1)
				(type default)
			)
			(layer "F.Fab")
		)
		(fp_line
			(start -0.12065 0.3048)
			(end -0.67945 0.3048)
			(stroke
				(width 0.1)
				(type default)
			)
			(layer "F.Fab")
		)
		(fp_line
			(start 0.120396 0.3048)
			(end 0.120396 0.2794)
			(stroke
				(width 0.1)
				(type default)
			)
			(layer "F.Fab")
		)
		(fp_line
			(start 0.67945 0.3048)
			(end 0.120396 0.3048)
			(stroke
				(width 0.1)
				(type default)
			)
			(layer "F.Fab")
		)
		(fp_line
			(start -0.12065 0.2794)
			(end -0.12065 0.3048)
			(stroke
				(width 0.1)
				(type default)
			)
			(layer "F.Fab")
		)
		(fp_line
			(start 0.120396 0.2794)
			(end -0.12065 0.2794)
			(stroke
				(width 0.1)
				(type default)
			)
			(layer "F.Fab")
		)
		(fp_line
			(start -0.12065 -0.2794)
			(end 0.12065 -0.2794)
			(stroke
				(width 0.1)
				(type default)
			)
			(layer "F.Fab")
		)
		(fp_line
			(start 0.12065 -0.2794)
			(end 0.12065 -0.3048)
			(stroke
				(width 0.1)
				(type default)
			)
			(layer "F.Fab")
		)
		(fp_line
			(start 0.12065 -0.3048)
			(end 0.67945 -0.3048)
			(stroke
				(width 0.1)
				(type default)
			)
			(layer "F.Fab")
		)
		(fp_line
			(start 0.67945 -0.3048)
			(end 0.67945 0.3048)
			(stroke
				(width 0.1)
				(type default)
			)
			(layer "F.Fab")
		)
		(fp_line
			(start -0.67945 -0.305054)
			(end -0.12065 -0.305054)
			(stroke
				(width 0.1)
				(type default)
			)
			(layer "F.Fab")
		)
		(fp_line
			(start -0.12065 -0.305054)
			(end -0.12065 -0.2794)
			(stroke
				(width 0.1)
				(type default)
			)
			(layer "F.Fab")
		)
		(pad "1" smd circle
			(at -0.40005 0 270)
			(size 0 0)
			(layers "F.Cu" "F.Mask" "F.Paste")
			(net "P12V_OCP_SFF_EN_R")
		)
		(pad "2" smd circle
			(at 0.40005 0 270)
			(size 0 0)
			(layers "F.Cu" "F.Mask" "F.Paste")
			(net "P12V_OCP_EN_1_R2")
		)
	)
	(footprint ""
		(layer "F.Cu")
		(at 119.362728 -173.657768 -90)
		(property "Reference" "PR525"
			(at 0 0 270)
			(layer "F.SilkS")
			(hide yes)
			(effects
				(font
					(size 1.27 1.27)
				)
			)
		)
		(property "Value" ""
			(at 0 0 270)
			(layer "F.Fab")
			(effects
				(font
					(size 1.27 1.27)
				)
			)
		)
		(duplicate_pad_numbers_are_jumpers no)
		(fp_line
			(start -0.7874 0.4064)
			(end -0.7874 -0.4064)
			(stroke
				(width 0.1524)
				(type default)
			)
			(layer "F.SilkS")
		)
		(fp_line
			(start 0.7874 0.4064)
			(end -0.7874 0.4064)
			(stroke
				(width 0.1524)
				(type default)
			)
			(layer "F.SilkS")
		)
		(fp_line
			(start -0.7874 -0.4064)
			(end 0.7874 -0.4064)
			(stroke
				(width 0.1524)
				(type default)
			)
			(layer "F.SilkS")
		)
		(fp_line
			(start 0.7874 -0.4064)
			(end 0.7874 0.4064)
			(stroke
				(width 0.1524)
				(type default)
			)
			(layer "F.SilkS")
		)
		(fp_line
			(start -0.67945 0.3048)
			(end -0.67945 -0.305054)
			(stroke
				(width 0.1)
				(type default)
			)
			(layer "F.Fab")
		)
		(fp_line
			(start -0.12065 0.3048)
			(end -0.67945 0.3048)
			(stroke
				(width 0.1)
				(type default)
			)
			(layer "F.Fab")
		)
		(fp_line
			(start 0.120396 0.3048)
			(end 0.120396 0.2794)
			(stroke
				(width 0.1)
				(type default)
			)
			(layer "F.Fab")
		)
		(fp_line
			(start 0.67945 0.3048)
			(end 0.120396 0.3048)
			(stroke
				(width 0.1)
				(type default)
			)
			(layer "F.Fab")
		)
		(fp_line
			(start -0.12065 0.2794)
			(end -0.12065 0.3048)
			(stroke
				(width 0.1)
				(type default)
			)
			(layer "F.Fab")
		)
		(fp_line
			(start 0.120396 0.2794)
			(end -0.12065 0.2794)
			(stroke
				(width 0.1)
				(type default)
			)
			(layer "F.Fab")
		)
		(fp_line
			(start -0.12065 -0.2794)
			(end 0.12065 -0.2794)
			(stroke
				(width 0.1)
				(type default)
			)
			(layer "F.Fab")
		)
		(fp_line
			(start 0.12065 -0.2794)
			(end 0.12065 -0.3048)
			(stroke
				(width 0.1)
				(type default)
			)
			(layer "F.Fab")
		)
		(fp_line
			(start 0.12065 -0.3048)
			(end 0.67945 -0.3048)
			(stroke
				(width 0.1)
				(type default)
			)
			(layer "F.Fab")
		)
		(fp_line
			(start 0.67945 -0.3048)
			(end 0.67945 0.3048)
			(stroke
				(width 0.1)
				(type default)
			)
			(layer "F.Fab")
		)
		(fp_line
			(start -0.67945 -0.305054)
			(end -0.12065 -0.305054)
			(stroke
				(width 0.1)
				(type default)
			)
			(layer "F.Fab")
		)
		(fp_line
			(start -0.12065 -0.305054)
			(end -0.12065 -0.2794)
			(stroke
				(width 0.1)
				(type default)
			)
			(layer "F.Fab")
		)
		(pad "1" smd circle
			(at -0.40005 0 270)
			(size 0 0)
			(layers "F.Cu" "F.Mask" "F.Paste")
			(net "SW_PVDDCR_SOC_P1_SW1_RC")
		)
		(pad "2" smd circle
			(at 0.40005 0 270)
			(size 0 0)
			(layers "F.Cu" "F.Mask" "F.Paste")
			(net "GND")
		)
	)
	(footprint ""
		(layer "F.Cu")
		(at 173.899322 -28.03779 -90)
		(property "Reference" "PR4011"
			(at 0 0 270)
			(layer "F.SilkS")
			(hide yes)
			(effects
				(font
					(size 1.27 1.27)
				)
			)
		)
		(property "Value" ""
			(at 0 0 270)
			(layer "F.Fab")
			(effects
				(font
					(size 1.27 1.27)
				)
			)
		)
		(duplicate_pad_numbers_are_jumpers no)
		(fp_line
			(start -0.7874 0.4064)
			(end -0.7874 -0.4064)
			(stroke
				(width 0.1524)
				(type default)
			)
			(layer "F.SilkS")
		)
		(fp_line
			(start 0.7874 0.4064)
			(end -0.7874 0.4064)
			(stroke
				(width 0.1524)
				(type default)
			)
			(layer "F.SilkS")
		)
		(fp_line
			(start -0.7874 -0.4064)
			(end 0.7874 -0.4064)
			(stroke
				(width 0.1524)
				(type default)
			)
			(layer "F.SilkS")
		)
		(fp_line
			(start 0.7874 -0.4064)
			(end 0.7874 0.4064)
			(stroke
				(width 0.1524)
				(type default)
			)
			(layer "F.SilkS")
		)
		(fp_line
			(start -0.67945 0.3048)
			(end -0.67945 -0.305054)
			(stroke
				(width 0.1)
				(type default)
			)
			(layer "F.Fab")
		)
		(fp_line
			(start -0.12065 0.3048)
			(end -0.67945 0.3048)
			(stroke
				(width 0.1)
				(type default)
			)
			(layer "F.Fab")
		)
		(fp_line
			(start 0.120396 0.3048)
			(end 0.120396 0.2794)
			(stroke
				(width 0.1)
				(type default)
			)
			(layer "F.Fab")
		)
		(fp_line
			(start 0.67945 0.3048)
			(end 0.120396 0.3048)
			(stroke
				(width 0.1)
				(type default)
			)
			(layer "F.Fab")
		)
		(fp_line
			(start -0.12065 0.2794)
			(end -0.12065 0.3048)
			(stroke
				(width 0.1)
				(type default)
			)
			(layer "F.Fab")
		)
		(fp_line
			(start 0.120396 0.2794)
			(end -0.12065 0.2794)
			(stroke
				(width 0.1)
				(type default)
			)
			(layer "F.Fab")
		)
		(fp_line
			(start -0.12065 -0.2794)
			(end 0.12065 -0.2794)
			(stroke
				(width 0.1)
				(type default)
			)
			(layer "F.Fab")
		)
		(fp_line
			(start 0.12065 -0.2794)
			(end 0.12065 -0.3048)
			(stroke
				(width 0.1)
				(type default)
			)
			(layer "F.Fab")
		)
		(fp_line
			(start 0.12065 -0.3048)
			(end 0.67945 -0.3048)
			(stroke
				(width 0.1)
				(type default)
			)
			(layer "F.Fab")
		)
		(fp_line
			(start 0.67945 -0.3048)
			(end 0.67945 0.3048)
			(stroke
				(width 0.1)
				(type default)
			)
			(layer "F.Fab")
		)
		(fp_line
			(start -0.67945 -0.305054)
			(end -0.12065 -0.305054)
			(stroke
				(width 0.1)
				(type default)
			)
			(layer "F.Fab")
		)
		(fp_line
			(start -0.12065 -0.305054)
			(end -0.12065 -0.2794)
			(stroke
				(width 0.1)
				(type default)
			)
			(layer "F.Fab")
		)
		(pad "1" smd circle
			(at -0.40005 0 270)
			(size 0 0)
			(layers "F.Cu" "F.Mask" "F.Paste")
			(net "P12V_SCM_OV_FB")
		)
		(pad "2" smd circle
			(at 0.40005 0 270)
			(size 0 0)
			(layers "F.Cu" "F.Mask" "F.Paste")
			(net "GND")
		)
	)
)
